# S9S_MB_2U (Grand Teton) — schematic netlist excerpt (pin names and nets, part order shuffled) for the footprints in the layout excerpt that follows; sources: Cadence DE-HDL packaged netlist, KiCad conversion of 03242023_DA0F0TMBIJ0_F0T_Motherboard_J_brd_V01_OCP.brd

R3612  Q_RES  4.7K 1% EMPTY  pkg 0402LF  page 172 : A = GND ; B = INA230_5_A1
C960  Q_CAP_DIFFBUS  DIFF BUS_0.22UF 6.3V 20% X6S  pkg C0201  page 173 : \1\ = P5E_CPU0_PE2_TX_C_DN<2> ; \2\ = P5E_CPU0_PE2_TX_DN<2>
R4654  Q_RES  1K 1% CHIP  pkg 0402LF  page 167 : A = FM_P2E_BUF2_EQA1 ; B = GND

(kicad_pcb
	(version 20260206)
	(generator "pcbnew")
	(generator_version "10.0")
	(general
		(thickness 1.6)
		(legacy_teardrops no)
	)
	(paper "A4")
	(title_block
		(title "03242023_DA0F0TMBIJ0_F0T_Motherboard_J_brd_V01_OCP.brd")
		(comment 1 "Grand Teton / footprints 2523-2525 of 6105")
	)
	(layers
		(0 "F.Cu" signal "TOP")
		(4 "In1.Cu" signal "GND")
		(6 "In2.Cu" signal "IN1")
		(8 "In3.Cu" signal "GND1")
		(10 "In4.Cu" signal "IN2")
		(12 "In5.Cu" signal "GND2")
		(14 "In6.Cu" signal "IN3")
		(16 "In7.Cu" signal "GND3")
		(18 "In8.Cu" signal "VCC")
		(20 "In9.Cu" signal "VCC1")
		(22 "In10.Cu" signal "GND4")
		(24 "In11.Cu" signal "IN4")
		(26 "In12.Cu" signal "GND5")
		(28 "In13.Cu" signal "IN5")
		(30 "In14.Cu" signal "GND6")
		(32 "In15.Cu" signal "IN6")
		(34 "In16.Cu" signal "GND7")
		(2 "B.Cu" signal "BOTTOM")
		(9 "F.Adhes" user "F.Adhesive")
		(11 "B.Adhes" user "B.Adhesive")
		(13 "F.Paste" user "Package Geometry/Pastemask Top")
		(15 "B.Paste" user "Package Geometry/Pastemask Bottom")
		(5 "F.SilkS" user "Ref Des/Silkscreen Top")
		(7 "B.SilkS" user "Ref Des/Silkscreen Bottom")
		(1 "F.Mask" user "Board Geometry/Soldermask Top")
		(3 "B.Mask" user "Board Geometry/Soldermask Bottom")
		(17 "Dwgs.User" user "User.Drawings")
		(19 "Cmts.User" user "User.Comments")
		(21 "Eco1.User" user "User.Eco1")
		(23 "Eco2.User" user "User.Eco2")
		(25 "Edge.Cuts" user "Board Geometry/Outline")
		(27 "Margin" user)
		(31 "F.CrtYd" user "Package Geometry/Place Bound Top")
		(29 "B.CrtYd" user "Package Geometry/Place Bound Bottom")
		(35 "F.Fab" user "Ref Des/Assembly Top")
		(33 "B.Fab" user "Ref Des/Assembly Bottom")
	)
	(footprint ""
		(layer "F.Cu")
		(at 40.413178 -397.406622 90)
		(property "Reference" "R4654"
			(at 0 0 90)
			(layer "F.SilkS")
			(hide yes)
			(effects
				(font
					(size 1.27 1.27)
				)
			)
		)
		(property "Value" ""
			(at 0 0 90)
			(layer "F.Fab")
			(effects
				(font
					(size 1.27 1.27)
				)
			)
		)
		(duplicate_pad_numbers_are_jumpers no)
		(fp_line
			(start 0.7874 -0.4064)
			(end 0.7874 0.4064)
			(stroke
				(width 0.1524)
				(type default)
			)
			(layer "F.SilkS")
		)
		(fp_line
			(start -0.7874 -0.4064)
			(end 0.7874 -0.4064)
			(stroke
				(width 0.1524)
				(type default)
			)
			(layer "F.SilkS")
		)
		(fp_line
			(start 0.7874 0.4064)
			(end -0.7874 0.4064)
			(stroke
				(width 0.1524)
				(type default)
			)
			(layer "F.SilkS")
		)
		(fp_line
			(start -0.7874 0.4064)
			(end -0.7874 -0.4064)
			(stroke
				(width 0.1524)
				(type default)
			)
			(layer "F.SilkS")
		)
		(fp_line
			(start -0.12065 -0.305054)
			(end -0.12065 -0.2794)
			(stroke
				(width 0.1)
				(type default)
			)
			(layer "F.Fab")
		)
		(fp_line
			(start -0.67945 -0.305054)
			(end -0.12065 -0.305054)
			(stroke
				(width 0.1)
				(type default)
			)
			(layer "F.Fab")
		)
		(fp_line
			(start 0.67945 -0.3048)
			(end 0.67945 0.3048)
			(stroke
				(width 0.1)
				(type default)
			)
			(layer "F.Fab")
		)
		(fp_line
			(start 0.12065 -0.3048)
			(end 0.67945 -0.3048)
			(stroke
				(width 0.1)
				(type default)
			)
			(layer "F.Fab")
		)
		(fp_line
			(start 0.12065 -0.2794)
			(end 0.12065 -0.3048)
			(stroke
				(width 0.1)
				(type default)
			)
			(layer "F.Fab")
		)
		(fp_line
			(start -0.12065 -0.2794)
			(end 0.12065 -0.2794)
			(stroke
				(width 0.1)
				(type default)
			)
			(layer "F.Fab")
		)
		(fp_line
			(start 0.120396 0.2794)
			(end -0.12065 0.2794)
			(stroke
				(width 0.1)
				(type default)
			)
			(layer "F.Fab")
		)
		(fp_line
			(start -0.12065 0.2794)
			(end -0.12065 0.3048)
			(stroke
				(width 0.1)
				(type default)
			)
			(layer "F.Fab")
		)
		(fp_line
			(start 0.67945 0.3048)
			(end 0.120396 0.3048)
			(stroke
				(width 0.1)
				(type default)
			)
			(layer "F.Fab")
		)
		(fp_line
			(start 0.120396 0.3048)
			(end 0.120396 0.2794)
			(stroke
				(width 0.1)
				(type default)
			)
			(layer "F.Fab")
		)
		(fp_line
			(start -0.12065 0.3048)
			(end -0.67945 0.3048)
			(stroke
				(width 0.1)
				(type default)
			)
			(layer "F.Fab")
		)
		(fp_line
			(start -0.67945 0.3048)
			(end -0.67945 -0.305054)
			(stroke
				(width 0.1)
				(type default)
			)
			(layer "F.Fab")
		)
		(pad "1" smd circle
			(at -0.40005 0 90)
			(size 0 0)
			(layers "F.Cu" "F.Mask" "F.Paste")
			(net "FM_P2E_BUF2_EQA1")
		)
		(pad "2" smd circle
			(at 0.40005 0 90)
			(size 0 0)
			(layers "F.Cu" "F.Mask" "F.Paste")
			(net "GND")
		)
	)
	(footprint ""
		(layer "F.Cu")
		(at 208.054956 -30.276292 90)
		(property "Reference" "R3612"
			(at 0 0 90)
			(layer "F.SilkS")
			(hide yes)
			(effects
				(font
					(size 1.27 1.27)
				)
			)
		)
		(property "Value" ""
			(at 0 0 90)
			(layer "F.Fab")
			(effects
				(font
					(size 1.27 1.27)
				)
			)
		)
		(duplicate_pad_numbers_are_jumpers no)
		(fp_line
			(start 0.7874 -0.4064)
			(end 0.7874 0.4064)
			(stroke
				(width 0.1524)
				(type default)
			)
			(layer "F.SilkS")
		)
		(fp_line
			(start -0.7874 -0.4064)
			(end 0.7874 -0.4064)
			(stroke
				(width 0.1524)
				(type default)
			)
			(layer "F.SilkS")
		)
		(fp_line
			(start 0.7874 0.4064)
			(end -0.7874 0.4064)
			(stroke
				(width 0.1524)
				(type default)
			)
			(layer "F.SilkS")
		)
		(fp_line
			(start -0.7874 0.4064)
			(end -0.7874 -0.4064)
			(stroke
				(width 0.1524)
				(type default)
			)
			(layer "F.SilkS")
		)
		(fp_line
			(start -0.12065 -0.305054)
			(end -0.12065 -0.2794)
			(stroke
				(width 0.1)
				(type default)
			)
			(layer "F.Fab")
		)
		(fp_line
			(start -0.67945 -0.305054)
			(end -0.12065 -0.305054)
			(stroke
				(width 0.1)
				(type default)
			)
			(layer "F.Fab")
		)
		(fp_line
			(start 0.67945 -0.3048)
			(end 0.67945 0.3048)
			(stroke
				(width 0.1)
				(type default)
			)
			(layer "F.Fab")
		)
		(fp_line
			(start 0.12065 -0.3048)
			(end 0.67945 -0.3048)
			(stroke
				(width 0.1)
				(type default)
			)
			(layer "F.Fab")
		)
		(fp_line
			(start 0.12065 -0.2794)
			(end 0.12065 -0.3048)
			(stroke
				(width 0.1)
				(type default)
			)
			(layer "F.Fab")
		)
		(fp_line
			(start -0.12065 -0.2794)
			(end 0.12065 -0.2794)
			(stroke
				(width 0.1)
				(type default)
			)
			(layer "F.Fab")
		)
		(fp_line
			(start 0.120396 0.2794)
			(end -0.12065 0.2794)
			(stroke
				(width 0.1)
				(type default)
			)
			(layer "F.Fab")
		)
		(fp_line
			(start -0.12065 0.2794)
			(end -0.12065 0.3048)
			(stroke
				(width 0.1)
				(type default)
			)
			(layer "F.Fab")
		)
		(fp_line
			(start 0.67945 0.3048)
			(end 0.120396 0.3048)
			(stroke
				(width 0.1)
				(type default)
			)
			(layer "F.Fab")
		)
		(fp_line
			(start 0.120396 0.3048)
			(end 0.120396 0.2794)
			(stroke
				(width 0.1)
				(type default)
			)
			(layer "F.Fab")
		)
		(fp_line
			(start -0.12065 0.3048)
			(end -0.67945 0.3048)
			(stroke
				(width 0.1)
				(type default)
			)
			(layer "F.Fab")
		)
		(fp_line
			(start -0.67945 0.3048)
			(end -0.67945 -0.305054)
			(stroke
				(width 0.1)
				(type default)
			)
			(layer "F.Fab")
		)
		(pad "1" smd circle
			(at -0.40005 0 90)
			(size 0 0)
			(layers "F.Cu" "F.Mask" "F.Paste")
			(net "GND")
		)
		(pad "2" smd circle
			(at 0.40005 0 90)
			(size 0 0)
			(layers "F.Cu" "F.Mask" "F.Paste")
			(net "INA230_5_A1")
		)
	)
	(footprint ""
		(layer "F.Cu")
		(at 412.13405 -402.371052 -90)
		(property "Reference" "C960"
			(at 0 0 270)
			(layer "F.SilkS")
			(hide yes)
			(effects
				(font
					(size 1.27 1.27)
				)
			)
		)
		(property "Value" ""
			(at 0 0 270)
			(layer "F.Fab")
			(effects
				(font
					(size 1.27 1.27)
				)
			)
		)
		(duplicate_pad_numbers_are_jumpers no)
		(fp_line
			(start -0.299974 0.150114)
			(end -0.299974 -0.150114)
			(stroke
				(width 0.1)
				(type default)
			)
			(layer "F.Fab")
		)
		(fp_line
			(start 0.299974 0.150114)
			(end -0.299974 0.150114)
			(stroke
				(width 0.1)
				(type default)
			)
			(layer "F.Fab")
		)
		(fp_line
			(start -0.299974 -0.150114)
			(end 0.299974 -0.150114)
			(stroke
				(width 0.1)
				(type default)
			)
			(layer "F.Fab")
		)
		(fp_line
			(start 0.299974 -0.150114)
			(end 0.299974 0.150114)
			(stroke
				(width 0.1)
				(type default)
			)
			(layer "F.Fab")
		)
		(pad "1" smd rect
			(at -0.2667 0 270)
			(size 0.3048 0.381)
			(layers "F.Cu" "F.Mask" "F.Paste")
			(net "P5E_CPU0_PE2_TX_C_DN<2>")
		)
		(pad "2" smd rect
			(at 0.2667 0 270)
			(size 0.3048 0.381)
			(layers "F.Cu" "F.Mask" "F.Paste")
			(net "P5E_CPU0_PE2_TX_DN<2>")
		)
	)
)
